(kicad_pcb
	(version 20260206)
	(generator "pcbnew")
	(generator_version "10.0")
	(general
		(thickness 1.6)
		(legacy_teardrops no)
	)
	(paper "A4")
	(title_block
		(title "01162023_DA0F0TEBIF0_F0T_Expander_BD_F_brd_V02_OCP.brd")
		(comment 1 "Grand Teton / footprints 6518-6525 of 9728")
	)
	(layers
		(0 "F.Cu" signal "TOP")
		(4 "In1.Cu" signal "GND")
		(6 "In2.Cu" signal "VCC")
		(8 "In3.Cu" signal "VCC1")
		(10 "In4.Cu" signal "GND1")
		(12 "In5.Cu" signal "IN1")
		(14 "In6.Cu" signal "GND2")
		(16 "In7.Cu" signal "IN2")
		(18 "In8.Cu" signal "GND3")
		(20 "In9.Cu" signal "IN3")
		(22 "In10.Cu" signal "GND4")
		(24 "In11.Cu" signal "IN4")
		(26 "In12.Cu" signal "GND5")
		(28 "In13.Cu" signal "IN5")
		(30 "In14.Cu" signal "GND6")
		(32 "In15.Cu" signal "IN6")
		(34 "In16.Cu" signal "GND7")
		(2 "B.Cu" signal "BOTTOM")
		(9 "F.Adhes" user "F.Adhesive")
		(11 "B.Adhes" user "B.Adhesive")
		(13 "F.Paste" user "Package Geometry/Pastemask Top")
		(15 "B.Paste" user "Package Geometry/Pastemask Bottom")
		(5 "F.SilkS" user "Ref Des/Silkscreen Top")
		(7 "B.SilkS" user "Ref Des/Silkscreen Bottom")
		(1 "F.Mask" user "Board Geometry/Soldermask Top")
		(3 "B.Mask" user "Board Geometry/Soldermask Bottom")
		(17 "Dwgs.User" user "User.Drawings")
		(19 "Cmts.User" user "User.Comments")
		(21 "Eco1.User" user "User.Eco1")
		(23 "Eco2.User" user "User.Eco2")
		(25 "Edge.Cuts" user "Board Geometry/Outline")
		(27 "Margin" user)
		(31 "F.CrtYd" user "Package Geometry/Place Bound Top")
		(29 "B.CrtYd" user "Package Geometry/Place Bound Bottom")
		(35 "F.Fab" user "Ref Des/Assembly Top")
		(33 "B.Fab" user "Ref Des/Assembly Bottom")
	)
	(footprint ""
		(layer "F.Cu")
		(at 58.686192 -384.702812)
		(property "Reference" "R1834"
			(at 0 0 0)
			(layer "F.SilkS")
			(hide yes)
			(effects
				(font
					(size 1.27 1.27)
				)
			)
		)
		(property "Value" ""
			(at 0 0 0)
			(layer "F.Fab")
			(effects
				(font
					(size 1.27 1.27)
				)
			)
		)
		(duplicate_pad_numbers_are_jumpers no)
		(fp_line
			(start -0.7874 -0.4064)
			(end 0.7874 -0.4064)
			(stroke
				(width 0.1524)
				(type default)
			)
			(layer "F.SilkS")
		)
		(fp_line
			(start -0.7874 0.4064)
			(end -0.7874 -0.4064)
			(stroke
				(width 0.1524)
				(type default)
			)
			(layer "F.SilkS")
		)
		(fp_line
			(start 0.7874 -0.4064)
			(end 0.7874 0.4064)
			(stroke
				(width 0.1524)
				(type default)
			)
			(layer "F.SilkS")
		)
		(fp_line
			(start 0.7874 0.4064)
			(end -0.7874 0.4064)
			(stroke
				(width 0.1524)
				(type default)
			)
			(layer "F.SilkS")
		)
		(fp_line
			(start -0.67945 -0.305054)
			(end -0.12065 -0.305054)
			(stroke
				(width 0.1)
				(type default)
			)
			(layer "F.Fab")
		)
		(fp_line
			(start -0.67945 0.3048)
			(end -0.67945 -0.305054)
			(stroke
				(width 0.1)
				(type default)
			)
			(layer "F.Fab")
		)
		(fp_line
			(start -0.12065 -0.305054)
			(end -0.12065 -0.2794)
			(stroke
				(width 0.1)
				(type default)
			)
			(layer "F.Fab")
		)
		(fp_line
			(start -0.12065 -0.2794)
			(end 0.12065 -0.2794)
			(stroke
				(width 0.1)
				(type default)
			)
			(layer "F.Fab")
		)
		(fp_line
			(start -0.12065 0.2794)
			(end -0.12065 0.3048)
			(stroke
				(width 0.1)
				(type default)
			)
			(layer "F.Fab")
		)
		(fp_line
			(start -0.12065 0.3048)
			(end -0.67945 0.3048)
			(stroke
				(width 0.1)
				(type default)
			)
			(layer "F.Fab")
		)
		(fp_line
			(start 0.120396 0.2794)
			(end -0.12065 0.2794)
			(stroke
				(width 0.1)
				(type default)
			)
			(layer "F.Fab")
		)
		(fp_line
			(start 0.120396 0.3048)
			(end 0.120396 0.2794)
			(stroke
				(width 0.1)
				(type default)
			)
			(layer "F.Fab")
		)
		(fp_line
			(start 0.12065 -0.3048)
			(end 0.67945 -0.3048)
			(stroke
				(width 0.1)
				(type default)
			)
			(layer "F.Fab")
		)
		(fp_line
			(start 0.12065 -0.2794)
			(end 0.12065 -0.3048)
			(stroke
				(width 0.1)
				(type default)
			)
			(layer "F.Fab")
		)
		(fp_line
			(start 0.67945 -0.3048)
			(end 0.67945 0.3048)
			(stroke
				(width 0.1)
				(type default)
			)
			(layer "F.Fab")
		)
		(fp_line
			(start 0.67945 0.3048)
			(end 0.120396 0.3048)
			(stroke
				(width 0.1)
				(type default)
			)
			(layer "F.Fab")
		)
		(pad "1" smd circle
			(at -0.40005 0)
			(size 0 0)
			(layers "F.Cu" "F.Mask" "F.Paste")
			(net "GPU_PEX_STRAP1_R")
		)
		(pad "2" smd circle
			(at 0.40005 0)
			(size 0 0)
			(layers "F.Cu" "F.Mask" "F.Paste")
			(net "GPU_PEX_STRAP1")
		)
	)
	(footprint ""
		(layer "F.Cu")
		(at 131.39674 -118.378986 -90)
		(property "Reference" "R5954"
			(at 0 0 270)
			(layer "F.SilkS")
			(hide yes)
			(effects
				(font
					(size 1.27 1.27)
				)
			)
		)
		(property "Value" ""
			(at 0 0 270)
			(layer "F.Fab")
			(effects
				(font
					(size 1.27 1.27)
				)
			)
		)
		(duplicate_pad_numbers_are_jumpers no)
		(fp_line
			(start -0.7874 0.4064)
			(end -0.7874 -0.4064)
			(stroke
				(width 0.1524)
				(type default)
			)
			(layer "F.SilkS")
		)
		(fp_line
			(start 0.7874 0.4064)
			(end -0.7874 0.4064)
			(stroke
				(width 0.1524)
				(type default)
			)
			(layer "F.SilkS")
		)
		(fp_line
			(start -0.7874 -0.4064)
			(end 0.7874 -0.4064)
			(stroke
				(width 0.1524)
				(type default)
			)
			(layer "F.SilkS")
		)
		(fp_line
			(start 0.7874 -0.4064)
			(end 0.7874 0.4064)
			(stroke
				(width 0.1524)
				(type default)
			)
			(layer "F.SilkS")
		)
		(fp_line
			(start -0.67945 0.3048)
			(end -0.67945 -0.305054)
			(stroke
				(width 0.1)
				(type default)
			)
			(layer "F.Fab")
		)
		(fp_line
			(start -0.12065 0.3048)
			(end -0.67945 0.3048)
			(stroke
				(width 0.1)
				(type default)
			)
			(layer "F.Fab")
		)
		(fp_line
			(start 0.120396 0.3048)
			(end 0.120396 0.2794)
			(stroke
				(width 0.1)
				(type default)
			)
			(layer "F.Fab")
		)
		(fp_line
			(start 0.67945 0.3048)
			(end 0.120396 0.3048)
			(stroke
				(width 0.1)
				(type default)
			)
			(layer "F.Fab")
		)
		(fp_line
			(start -0.12065 0.2794)
			(end -0.12065 0.3048)
			(stroke
				(width 0.1)
				(type default)
			)
			(layer "F.Fab")
		)
		(fp_line
			(start 0.120396 0.2794)
			(end -0.12065 0.2794)
			(stroke
				(width 0.1)
				(type default)
			)
			(layer "F.Fab")
		)
		(fp_line
			(start -0.12065 -0.2794)
			(end 0.12065 -0.2794)
			(stroke
				(width 0.1)
				(type default)
			)
			(layer "F.Fab")
		)
		(fp_line
			(start 0.12065 -0.2794)
			(end 0.12065 -0.3048)
			(stroke
				(width 0.1)
				(type default)
			)
			(layer "F.Fab")
		)
		(fp_line
			(start 0.12065 -0.3048)
			(end 0.67945 -0.3048)
			(stroke
				(width 0.1)
				(type default)
			)
			(layer "F.Fab")
		)
		(fp_line
			(start 0.67945 -0.3048)
			(end 0.67945 0.3048)
			(stroke
				(width 0.1)
				(type default)
			)
			(layer "F.Fab")
		)
		(fp_line
			(start -0.67945 -0.305054)
			(end -0.12065 -0.305054)
			(stroke
				(width 0.1)
				(type default)
			)
			(layer "F.Fab")
		)
		(fp_line
			(start -0.12065 -0.305054)
			(end -0.12065 -0.2794)
			(stroke
				(width 0.1)
				(type default)
			)
			(layer "F.Fab")
		)
		(pad "1" smd circle
			(at -0.40005 0 270)
			(size 0 0)
			(layers "F.Cu" "F.Mask" "F.Paste")
			(net "HP_NIC2_EN")
		)
		(pad "2" smd circle
			(at 0.40005 0 270)
			(size 0 0)
			(layers "F.Cu" "F.Mask" "F.Paste")
			(net "P3V3_NIC2_CO_EN")
		)
	)
	(footprint ""
		(layer "F.Cu")
		(at 135.526018 -100.154486)
		(property "Reference" "C2709"
			(at 0 0 0)
			(layer "F.SilkS")
			(hide yes)
			(effects
				(font
					(size 1.27 1.27)
				)
			)
		)
		(property "Value" ""
			(at 0 0 0)
			(layer "F.Fab")
			(effects
				(font
					(size 1.27 1.27)
				)
			)
		)
		(duplicate_pad_numbers_are_jumpers no)
		(fp_line
			(start -0.7874 -0.4064)
			(end 0.7874 -0.4064)
			(stroke
				(width 0.1524)
				(type default)
			)
			(layer "F.SilkS")
		)
		(fp_line
			(start -0.7874 0.4064)
			(end -0.7874 -0.4064)
			(stroke
				(width 0.1524)
				(type default)
			)
			(layer "F.SilkS")
		)
		(fp_line
			(start 0.7874 -0.4064)
			(end 0.7874 0.4064)
			(stroke
				(width 0.1524)
				(type default)
			)
			(layer "F.SilkS")
		)
		(fp_line
			(start 0.7874 0.4064)
			(end -0.7874 0.4064)
			(stroke
				(width 0.1524)
				(type default)
			)
			(layer "F.SilkS")
		)
		(fp_line
			(start -0.67945 -0.305054)
			(end -0.12065 -0.305054)
			(stroke
				(width 0.1)
				(type default)
			)
			(layer "F.Fab")
		)
		(fp_line
			(start -0.67945 0.3048)
			(end -0.67945 -0.305054)
			(stroke
				(width 0.1)
				(type default)
			)
			(layer "F.Fab")
		)
		(fp_line
			(start -0.12065 -0.305054)
			(end -0.12065 -0.2794)
			(stroke
				(width 0.1)
				(type default)
			)
			(layer "F.Fab")
		)
		(fp_line
			(start -0.12065 -0.2794)
			(end 0.12065 -0.2794)
			(stroke
				(width 0.1)
				(type default)
			)
			(layer "F.Fab")
		)
		(fp_line
			(start -0.12065 0.2794)
			(end -0.12065 0.3048)
			(stroke
				(width 0.1)
				(type default)
			)
			(layer "F.Fab")
		)
		(fp_line
			(start -0.12065 0.3048)
			(end -0.67945 0.3048)
			(stroke
				(width 0.1)
				(type default)
			)
			(layer "F.Fab")
		)
		(fp_line
			(start 0.120396 0.2794)
			(end -0.12065 0.2794)
			(stroke
				(width 0.1)
				(type default)
			)
			(layer "F.Fab")
		)
		(fp_line
			(start 0.120396 0.3048)
			(end 0.120396 0.2794)
			(stroke
				(width 0.1)
				(type default)
			)
			(layer "F.Fab")
		)
		(fp_line
			(start 0.12065 -0.3048)
			(end 0.67945 -0.3048)
			(stroke
				(width 0.1)
				(type default)
			)
			(layer "F.Fab")
		)
		(fp_line
			(start 0.12065 -0.2794)
			(end 0.12065 -0.3048)
			(stroke
				(width 0.1)
				(type default)
			)
			(layer "F.Fab")
		)
		(fp_line
			(start 0.67945 -0.3048)
			(end 0.67945 0.3048)
			(stroke
				(width 0.1)
				(type default)
			)
			(layer "F.Fab")
		)
		(fp_line
			(start 0.67945 0.3048)
			(end 0.120396 0.3048)
			(stroke
				(width 0.1)
				(type default)
			)
			(layer "F.Fab")
		)
		(pad "1" smd circle
			(at -0.40005 0)
			(size 0 0)
			(layers "F.Cu" "F.Mask" "F.Paste")
			(net "P3V3_AUX")
		)
		(pad "2" smd circle
			(at 0.40005 0)
			(size 0 0)
			(layers "F.Cu" "F.Mask" "F.Paste")
			(net "GND")
		)
	)
	(footprint ""
		(layer "F.Cu")
		(at 224.851976 -373.090186)
		(property "Reference" "PR30"
			(at 0 0 0)
			(layer "F.SilkS")
			(hide yes)
			(effects
				(font
					(size 1.27 1.27)
				)
			)
		)
		(property "Value" ""
			(at 0 0 0)
			(layer "F.Fab")
			(effects
				(font
					(size 1.27 1.27)
				)
			)
		)
		(duplicate_pad_numbers_are_jumpers no)
		(fp_line
			(start -0.7874 -0.4064)
			(end 0.7874 -0.4064)
			(stroke
				(width 0.1524)
				(type default)
			)
			(layer "F.SilkS")
		)
		(fp_line
			(start -0.7874 0.4064)
			(end -0.7874 -0.4064)
			(stroke
				(width 0.1524)
				(type default)
			)
			(layer "F.SilkS")
		)
		(fp_line
			(start 0.7874 -0.4064)
			(end 0.7874 0.4064)
			(stroke
				(width 0.1524)
				(type default)
			)
			(layer "F.SilkS")
		)
		(fp_line
			(start 0.7874 0.4064)
			(end -0.7874 0.4064)
			(stroke
				(width 0.1524)
				(type default)
			)
			(layer "F.SilkS")
		)
		(fp_line
			(start -0.67945 -0.305054)
			(end -0.12065 -0.305054)
			(stroke
				(width 0.1)
				(type default)
			)
			(layer "F.Fab")
		)
		(fp_line
			(start -0.67945 0.3048)
			(end -0.67945 -0.305054)
			(stroke
				(width 0.1)
				(type default)
			)
			(layer "F.Fab")
		)
		(fp_line
			(start -0.12065 -0.305054)
			(end -0.12065 -0.2794)
			(stroke
				(width 0.1)
				(type default)
			)
			(layer "F.Fab")
		)
		(fp_line
			(start -0.12065 -0.2794)
			(end 0.12065 -0.2794)
			(stroke
				(width 0.1)
				(type default)
			)
			(layer "F.Fab")
		)
		(fp_line
			(start -0.12065 0.2794)
			(end -0.12065 0.3048)
			(stroke
				(width 0.1)
				(type default)
			)
			(layer "F.Fab")
		)
		(fp_line
			(start -0.12065 0.3048)
			(end -0.67945 0.3048)
			(stroke
				(width 0.1)
				(type default)
			)
			(layer "F.Fab")
		)
		(fp_line
			(start 0.120396 0.2794)
			(end -0.12065 0.2794)
			(stroke
				(width 0.1)
				(type default)
			)
			(layer "F.Fab")
		)
		(fp_line
			(start 0.120396 0.3048)
			(end 0.120396 0.2794)
			(stroke
				(width 0.1)
				(type default)
			)
			(layer "F.Fab")
		)
		(fp_line
			(start 0.12065 -0.3048)
			(end 0.67945 -0.3048)
			(stroke
				(width 0.1)
				(type default)
			)
			(layer "F.Fab")
		)
		(fp_line
			(start 0.12065 -0.2794)
			(end 0.12065 -0.3048)
			(stroke
				(width 0.1)
				(type default)
			)
			(layer "F.Fab")
		)
		(fp_line
			(start 0.67945 -0.3048)
			(end 0.67945 0.3048)
			(stroke
				(width 0.1)
				(type default)
			)
			(layer "F.Fab")
		)
		(fp_line
			(start 0.67945 0.3048)
			(end 0.120396 0.3048)
			(stroke
				(width 0.1)
				(type default)
			)
			(layer "F.Fab")
		)
		(pad "1" smd circle
			(at -0.40005 0)
			(size 0 0)
			(layers "F.Cu" "F.Mask" "F.Paste")
			(net "HSC_FLT_TYPE_1")
		)
		(pad "2" smd circle
			(at 0.40005 0)
			(size 0 0)
			(layers "F.Cu" "F.Mask" "F.Paste")
			(net "HSC_FLT_TYPE_R")
		)
	)
	(footprint ""
		(layer "F.Cu")
		(at 18.619978 -15.649956 180)
		(property "Reference" "H128"
			(at 1.35636 2.69621 0)
			(unlocked yes)
			(layer "B.SilkS")
			(effects
				(font
					(size 0.7874 0.5842)
					(thickness 0.1524)
				)
				(justify left mirror)
			)
		)
		(property "Value" ""
			(at 0 0 180)
			(layer "F.Fab")
			(effects
				(font
					(size 1.27 1.27)
				)
			)
		)
		(duplicate_pad_numbers_are_jumpers no)
		(pad "1" thru_hole rect
			(at 0 0 180)
			(size 4.2164 5.0038)
			(drill 2.0066
				(offset 0.099822 0)
			)
			(layers "*.Cu" "*.Mask")
			(remove_unused_layers no)
			(net "Net_8535")
			(clearance -0.8509)
			(padstack
				(mode front_inner_back)
				(layer "Inner"
					(shape circle)
					(size 4.0132 4.0132)
					(clearance -0.7493)
				)
				(layer "B.Cu"
					(shape circle)
					(size 4.0132 4.0132)
					(clearance -0.7493)
				)
			)
		)
	)
	(footprint ""
		(layer "F.Cu")
		(at 198.76135 -124.076714 180)
		(property "Reference" "C237"
			(at 0 0 180)
			(layer "F.SilkS")
			(hide yes)
			(effects
				(font
					(size 1.27 1.27)
				)
			)
		)
		(property "Value" ""
			(at 0 0 180)
			(layer "F.Fab")
			(effects
				(font
					(size 1.27 1.27)
				)
			)
		)
		(duplicate_pad_numbers_are_jumpers no)
		(fp_line
			(start 0.299974 0.150114)
			(end -0.299974 0.150114)
			(stroke
				(width 0.1)
				(type default)
			)
			(layer "F.Fab")
		)
		(fp_line
			(start 0.299974 -0.150114)
			(end 0.299974 0.150114)
			(stroke
				(width 0.1)
				(type default)
			)
			(layer "F.Fab")
		)
		(fp_line
			(start -0.299974 0.150114)
			(end -0.299974 -0.150114)
			(stroke
				(width 0.1)
				(type default)
			)
			(layer "F.Fab")
		)
		(fp_line
			(start -0.299974 -0.150114)
			(end 0.299974 -0.150114)
			(stroke
				(width 0.1)
				(type default)
			)
			(layer "F.Fab")
		)
		(pad "1" smd rect
			(at -0.2667 0 180)
			(size 0.3048 0.381)
			(layers "F.Cu" "F.Mask" "F.Paste")
			(net "P5E_PEX1_STN0_TX_DN<3>")
		)
		(pad "2" smd rect
			(at 0.2667 0 180)
			(size 0.3048 0.381)
			(layers "F.Cu" "F.Mask" "F.Paste")
			(net "P5E_PEX1_STN0_TX_C_DN<3>")
		)
	)
	(footprint ""
		(layer "F.Cu")
		(at 267.718286 -252.356874 -90)
		(property "Reference" "R1368"
			(at 0 0 270)
			(layer "F.SilkS")
			(hide yes)
			(effects
				(font
					(size 1.27 1.27)
				)
			)
		)
		(property "Value" ""
			(at 0 0 270)
			(layer "F.Fab")
			(effects
				(font
					(size 1.27 1.27)
				)
			)
		)
		(duplicate_pad_numbers_are_jumpers no)
		(fp_line
			(start -0.7874 0.4064)
			(end -0.7874 -0.4064)
			(stroke
				(width 0.1524)
				(type default)
			)
			(layer "F.SilkS")
		)
		(fp_line
			(start 0.7874 0.4064)
			(end -0.7874 0.4064)
			(stroke
				(width 0.1524)
				(type default)
			)
			(layer "F.SilkS")
		)
		(fp_line
			(start -0.7874 -0.4064)
			(end 0.7874 -0.4064)
			(stroke
				(width 0.1524)
				(type default)
			)
			(layer "F.SilkS")
		)
		(fp_line
			(start 0.7874 -0.4064)
			(end 0.7874 0.4064)
			(stroke
				(width 0.1524)
				(type default)
			)
			(layer "F.SilkS")
		)
		(fp_line
			(start -0.67945 0.3048)
			(end -0.67945 -0.305054)
			(stroke
				(width 0.1)
				(type default)
			)
			(layer "F.Fab")
		)
		(fp_line
			(start -0.12065 0.3048)
			(end -0.67945 0.3048)
			(stroke
				(width 0.1)
				(type default)
			)
			(layer "F.Fab")
		)
		(fp_line
			(start 0.120396 0.3048)
			(end 0.120396 0.2794)
			(stroke
				(width 0.1)
				(type default)
			)
			(layer "F.Fab")
		)
		(fp_line
			(start 0.67945 0.3048)
			(end 0.120396 0.3048)
			(stroke
				(width 0.1)
				(type default)
			)
			(layer "F.Fab")
		)
		(fp_line
			(start -0.12065 0.2794)
			(end -0.12065 0.3048)
			(stroke
				(width 0.1)
				(type default)
			)
			(layer "F.Fab")
		)
		(fp_line
			(start 0.120396 0.2794)
			(end -0.12065 0.2794)
			(stroke
				(width 0.1)
				(type default)
			)
			(layer "F.Fab")
		)
		(fp_line
			(start -0.12065 -0.2794)
			(end 0.12065 -0.2794)
			(stroke
				(width 0.1)
				(type default)
			)
			(layer "F.Fab")
		)
		(fp_line
			(start 0.12065 -0.2794)
			(end 0.12065 -0.3048)
			(stroke
				(width 0.1)
				(type default)
			)
			(layer "F.Fab")
		)
		(fp_line
			(start 0.12065 -0.3048)
			(end 0.67945 -0.3048)
			(stroke
				(width 0.1)
				(type default)
			)
			(layer "F.Fab")
		)
		(fp_line
			(start 0.67945 -0.3048)
			(end 0.67945 0.3048)
			(stroke
				(width 0.1)
				(type default)
			)
			(layer "F.Fab")
		)
		(fp_line
			(start -0.67945 -0.305054)
			(end -0.12065 -0.305054)
			(stroke
				(width 0.1)
				(type default)
			)
			(layer "F.Fab")
		)
		(fp_line
			(start -0.12065 -0.305054)
			(end -0.12065 -0.2794)
			(stroke
				(width 0.1)
				(type default)
			)
			(layer "F.Fab")
		)
		(pad "1" smd circle
			(at -0.40005 0 270)
			(size 0 0)
			(layers "F.Cu" "F.Mask" "F.Paste")
			(net "GND")
		)
		(pad "2" smd circle
			(at 0.40005 0 270)
			(size 0 0)
			(layers "F.Cu" "F.Mask" "F.Paste")
			(net "PEX2_MODE_SEL12")
		)
	)
	(footprint ""
		(layer "F.Cu")
		(at 133.599428 -343.952322 90)
		(property "Reference" "C2269"
			(at 0 0 90)
			(layer "F.SilkS")
			(hide yes)
			(effects
				(font
					(size 1.27 1.27)
				)
			)
		)
		(property "Value" ""
			(at 0 0 90)
			(layer "F.Fab")
			(effects
				(font
					(size 1.27 1.27)
				)
			)
		)
		(duplicate_pad_numbers_are_jumpers no)
		(fp_line
			(start 0.299974 -0.150114)
			(end 0.299974 0.150114)
			(stroke
				(width 0.1)
				(type default)
			)
			(layer "F.Fab")
		)
		(fp_line
			(start -0.299974 -0.150114)
			(end 0.299974 -0.150114)
			(stroke
				(width 0.1)
				(type default)
			)
			(layer "F.Fab")
		)
		(fp_line
			(start 0.299974 0.150114)
			(end -0.299974 0.150114)
			(stroke
				(width 0.1)
				(type default)
			)
			(layer "F.Fab")
		)
		(fp_line
			(start -0.299974 0.150114)
			(end -0.299974 -0.150114)
			(stroke
				(width 0.1)
				(type default)
			)
			(layer "F.Fab")
		)
		(pad "1" smd rect
			(at -0.2667 0 90)
			(size 0.3048 0.381)
			(layers "F.Cu" "F.Mask" "F.Paste")
			(net "P5E_PEX1_STN5_TX_DP<82>")
		)
		(pad "2" smd rect
			(at 0.2667 0 90)
			(size 0.3048 0.381)
			(layers "F.Cu" "F.Mask" "F.Paste")
			(net "P5E_PEX1_STN5_TX_C_DP<82>")
		)
	)
)
